# T6G (Grand Teton) — schematic netlist excerpt (pin names and nets, part order shuffled) for the footprints in the layout excerpt that follows; sources: Cadence DE-HDL packaged netlist, KiCad conversion of 04192023_DAF0TMB3IC0_F0TG_MB_C_brd_V02_OCP.brd

PC227  Q_CAP  22UF 16V 20% X6S  pkg C0805  page 209 : A = SW_P12V_AUX_PVDD18_S5_P0_FLT ; B = GND
R1447  Q_RES  0 5% CHIP  pkg 0402LF  page 151 : A = SMB_CPU_5_SCL ; B = SMB_CPU_5_R1_SCL
PC6584  Q_CAP  100NF 50V 10% X7R  pkg C0402  page 363 : A = SW_P0V9_RETIMER_CPU0_BOOT2_RC ; B = SW_P0V9_RETIMER_CPU0_PH2

(kicad_pcb
	(version 20260206)
	(generator "pcbnew")
	(generator_version "10.0")
	(general
		(thickness 1.6)
		(legacy_teardrops no)
	)
	(paper "A4")
	(title_block
		(title "04192023_DAF0TMB3IC0_F0TG_MB_C_brd_V02_OCP.brd")
		(comment 1 "Grand Teton / footprints 1087-1089 of 8354")
	)
	(layers
		(0 "F.Cu" signal "TOP")
		(4 "In1.Cu" signal "GND")
		(6 "In2.Cu" signal "IN1")
		(8 "In3.Cu" signal "GND1")
		(10 "In4.Cu" signal "IN2")
		(12 "In5.Cu" signal "GND2")
		(14 "In6.Cu" signal "IN3")
		(16 "In7.Cu" signal "GND3")
		(18 "In8.Cu" signal "VCC")
		(20 "In9.Cu" signal "VCC1")
		(22 "In10.Cu" signal "GND4")
		(24 "In11.Cu" signal "IN4")
		(26 "In12.Cu" signal "GND5")
		(28 "In13.Cu" signal "IN5")
		(30 "In14.Cu" signal "GND6")
		(32 "In15.Cu" signal "IN6")
		(34 "In16.Cu" signal "GND7")
		(2 "B.Cu" signal "BOTTOM")
		(9 "F.Adhes" user "F.Adhesive")
		(11 "B.Adhes" user "B.Adhesive")
		(13 "F.Paste" user "Package Geometry/Pastemask Top")
		(15 "B.Paste" user "Package Geometry/Pastemask Bottom")
		(5 "F.SilkS" user "Ref Des/Silkscreen Top")
		(7 "B.SilkS" user "Ref Des/Silkscreen Bottom")
		(1 "F.Mask" user "Board Geometry/Soldermask Top")
		(3 "B.Mask" user "Board Geometry/Soldermask Bottom")
		(17 "Dwgs.User" user "User.Drawings")
		(19 "Cmts.User" user "User.Comments")
		(21 "Eco1.User" user "User.Eco1")
		(23 "Eco2.User" user "User.Eco2")
		(25 "Edge.Cuts" user "Board Geometry/Outline")
		(27 "Margin" user)
		(31 "F.CrtYd" user "Package Geometry/Place Bound Top")
		(29 "B.CrtYd" user "Package Geometry/Place Bound Bottom")
		(35 "F.Fab" user "Ref Des/Assembly Top")
		(33 "B.Fab" user "Ref Des/Assembly Bottom")
	)
	(footprint ""
		(layer "F.Cu")
		(at 456.131676 -401.709128 -90)
		(property "Reference" "PC6584"
			(at 0 0 270)
			(layer "F.SilkS")
			(hide yes)
			(effects
				(font
					(size 1.27 1.27)
				)
			)
		)
		(property "Value" ""
			(at 0 0 270)
			(layer "F.Fab")
			(effects
				(font
					(size 1.27 1.27)
				)
			)
		)
		(duplicate_pad_numbers_are_jumpers no)
		(fp_line
			(start -0.7874 0.4064)
			(end -0.7874 -0.4064)
			(stroke
				(width 0.1524)
				(type default)
			)
			(layer "F.SilkS")
		)
		(fp_line
			(start 0.7874 0.4064)
			(end -0.7874 0.4064)
			(stroke
				(width 0.1524)
				(type default)
			)
			(layer "F.SilkS")
		)
		(fp_line
			(start -0.7874 -0.4064)
			(end 0.7874 -0.4064)
			(stroke
				(width 0.1524)
				(type default)
			)
			(layer "F.SilkS")
		)
		(fp_line
			(start 0.7874 -0.4064)
			(end 0.7874 0.4064)
			(stroke
				(width 0.1524)
				(type default)
			)
			(layer "F.SilkS")
		)
		(fp_line
			(start -0.67945 0.3048)
			(end -0.67945 -0.305054)
			(stroke
				(width 0.1)
				(type default)
			)
			(layer "F.Fab")
		)
		(fp_line
			(start -0.12065 0.3048)
			(end -0.67945 0.3048)
			(stroke
				(width 0.1)
				(type default)
			)
			(layer "F.Fab")
		)
		(fp_line
			(start 0.120396 0.3048)
			(end 0.120396 0.2794)
			(stroke
				(width 0.1)
				(type default)
			)
			(layer "F.Fab")
		)
		(fp_line
			(start 0.67945 0.3048)
			(end 0.120396 0.3048)
			(stroke
				(width 0.1)
				(type default)
			)
			(layer "F.Fab")
		)
		(fp_line
			(start -0.12065 0.2794)
			(end -0.12065 0.3048)
			(stroke
				(width 0.1)
				(type default)
			)
			(layer "F.Fab")
		)
		(fp_line
			(start 0.120396 0.2794)
			(end -0.12065 0.2794)
			(stroke
				(width 0.1)
				(type default)
			)
			(layer "F.Fab")
		)
		(fp_line
			(start -0.12065 -0.2794)
			(end 0.12065 -0.2794)
			(stroke
				(width 0.1)
				(type default)
			)
			(layer "F.Fab")
		)
		(fp_line
			(start 0.12065 -0.2794)
			(end 0.12065 -0.3048)
			(stroke
				(width 0.1)
				(type default)
			)
			(layer "F.Fab")
		)
		(fp_line
			(start 0.12065 -0.3048)
			(end 0.67945 -0.3048)
			(stroke
				(width 0.1)
				(type default)
			)
			(layer "F.Fab")
		)
		(fp_line
			(start 0.67945 -0.3048)
			(end 0.67945 0.3048)
			(stroke
				(width 0.1)
				(type default)
			)
			(layer "F.Fab")
		)
		(fp_line
			(start -0.67945 -0.305054)
			(end -0.12065 -0.305054)
			(stroke
				(width 0.1)
				(type default)
			)
			(layer "F.Fab")
		)
		(fp_line
			(start -0.12065 -0.305054)
			(end -0.12065 -0.2794)
			(stroke
				(width 0.1)
				(type default)
			)
			(layer "F.Fab")
		)
		(pad "1" smd circle
			(at -0.40005 0 270)
			(size 0 0)
			(layers "F.Cu" "F.Mask" "F.Paste")
			(net "SW_P0V9_RETIMER_CPU0_BOOT2_RC")
		)
		(pad "2" smd circle
			(at 0.40005 0 270)
			(size 0 0)
			(layers "F.Cu" "F.Mask" "F.Paste")
			(net "SW_P0V9_RETIMER_CPU0_PH2")
		)
	)
	(footprint ""
		(layer "F.Cu")
		(at 190.119 -137.632948 -90)
		(property "Reference" "R1447"
			(at 0 0 270)
			(layer "F.SilkS")
			(hide yes)
			(effects
				(font
					(size 1.27 1.27)
				)
			)
		)
		(property "Value" ""
			(at 0 0 270)
			(layer "F.Fab")
			(effects
				(font
					(size 1.27 1.27)
				)
			)
		)
		(duplicate_pad_numbers_are_jumpers no)
		(fp_line
			(start -0.7874 0.4064)
			(end -0.7874 -0.4064)
			(stroke
				(width 0.1524)
				(type default)
			)
			(layer "F.SilkS")
		)
		(fp_line
			(start 0.7874 0.4064)
			(end -0.7874 0.4064)
			(stroke
				(width 0.1524)
				(type default)
			)
			(layer "F.SilkS")
		)
		(fp_line
			(start -0.7874 -0.4064)
			(end 0.7874 -0.4064)
			(stroke
				(width 0.1524)
				(type default)
			)
			(layer "F.SilkS")
		)
		(fp_line
			(start 0.7874 -0.4064)
			(end 0.7874 0.4064)
			(stroke
				(width 0.1524)
				(type default)
			)
			(layer "F.SilkS")
		)
		(fp_line
			(start -0.67945 0.3048)
			(end -0.67945 -0.305054)
			(stroke
				(width 0.1)
				(type default)
			)
			(layer "F.Fab")
		)
		(fp_line
			(start -0.12065 0.3048)
			(end -0.67945 0.3048)
			(stroke
				(width 0.1)
				(type default)
			)
			(layer "F.Fab")
		)
		(fp_line
			(start 0.120396 0.3048)
			(end 0.120396 0.2794)
			(stroke
				(width 0.1)
				(type default)
			)
			(layer "F.Fab")
		)
		(fp_line
			(start 0.67945 0.3048)
			(end 0.120396 0.3048)
			(stroke
				(width 0.1)
				(type default)
			)
			(layer "F.Fab")
		)
		(fp_line
			(start -0.12065 0.2794)
			(end -0.12065 0.3048)
			(stroke
				(width 0.1)
				(type default)
			)
			(layer "F.Fab")
		)
		(fp_line
			(start 0.120396 0.2794)
			(end -0.12065 0.2794)
			(stroke
				(width 0.1)
				(type default)
			)
			(layer "F.Fab")
		)
		(fp_line
			(start -0.12065 -0.2794)
			(end 0.12065 -0.2794)
			(stroke
				(width 0.1)
				(type default)
			)
			(layer "F.Fab")
		)
		(fp_line
			(start 0.12065 -0.2794)
			(end 0.12065 -0.3048)
			(stroke
				(width 0.1)
				(type default)
			)
			(layer "F.Fab")
		)
		(fp_line
			(start 0.12065 -0.3048)
			(end 0.67945 -0.3048)
			(stroke
				(width 0.1)
				(type default)
			)
			(layer "F.Fab")
		)
		(fp_line
			(start 0.67945 -0.3048)
			(end 0.67945 0.3048)
			(stroke
				(width 0.1)
				(type default)
			)
			(layer "F.Fab")
		)
		(fp_line
			(start -0.67945 -0.305054)
			(end -0.12065 -0.305054)
			(stroke
				(width 0.1)
				(type default)
			)
			(layer "F.Fab")
		)
		(fp_line
			(start -0.12065 -0.305054)
			(end -0.12065 -0.2794)
			(stroke
				(width 0.1)
				(type default)
			)
			(layer "F.Fab")
		)
		(pad "1" smd circle
			(at -0.40005 0 270)
			(size 0 0)
			(layers "F.Cu" "F.Mask" "F.Paste")
			(net "SMB_CPU_5_SCL")
		)
		(pad "2" smd circle
			(at 0.40005 0 270)
			(size 0 0)
			(layers "F.Cu" "F.Mask" "F.Paste")
			(net "SMB_CPU_5_R1_SCL")
		)
	)
	(footprint ""
		(layer "F.Cu")
		(at 336.172556 -137.25525)
		(property "Reference" "PC227"
			(at 0 0 0)
			(layer "F.SilkS")
			(hide yes)
			(effects
				(font
					(size 1.27 1.27)
				)
			)
		)
		(property "Value" ""
			(at 0 0 0)
			(layer "F.Fab")
			(effects
				(font
					(size 1.27 1.27)
				)
			)
		)
		(duplicate_pad_numbers_are_jumpers no)
		(fp_line
			(start -1.524 -0.762)
			(end 1.524 -0.762)
			(stroke
				(width 0.1524)
				(type default)
			)
			(layer "F.SilkS")
		)
		(fp_line
			(start -1.524 0.762)
			(end -1.524 -0.762)
			(stroke
				(width 0.1524)
				(type default)
			)
			(layer "F.SilkS")
		)
		(fp_line
			(start 1.524 -0.762)
			(end 1.524 0.762)
			(stroke
				(width 0.1524)
				(type default)
			)
			(layer "F.SilkS")
		)
		(fp_line
			(start 1.524 0.762)
			(end -1.524 0.762)
			(stroke
				(width 0.1524)
				(type default)
			)
			(layer "F.SilkS")
		)
		(fp_line
			(start -1.1049 -0.724916)
			(end -1.1049 0.724916)
			(stroke
				(width 0.1)
				(type default)
			)
			(layer "F.Fab")
		)
		(fp_line
			(start -1.1049 0.724916)
			(end 1.1049 0.724916)
			(stroke
				(width 0.1)
				(type default)
			)
			(layer "F.Fab")
		)
		(fp_line
			(start 1.1049 -0.724916)
			(end -1.1049 -0.724916)
			(stroke
				(width 0.1)
				(type default)
			)
			(layer "F.Fab")
		)
		(fp_line
			(start 1.1049 0.724916)
			(end 1.1049 -0.724916)
			(stroke
				(width 0.1)
				(type default)
			)
			(layer "F.Fab")
		)
		(pad "1" smd rect
			(at -0.889 0 180)
			(size 1.016 1.27)
			(layers "F.Cu" "F.Mask" "F.Paste")
			(net "SW_P12V_AUX_PVDD18_S5_P0_FLT")
		)
		(pad "2" smd rect
			(at 0.889 0 180)
			(size 1.016 1.27)
			(layers "F.Cu" "F.Mask" "F.Paste")
			(net "GND")
		)
	)
)
